(kicad_pcb
	(version 20260206)
	(generator "pcbnew")
	(generator_version "10.0")
	(general
		(thickness 1.6)
		(legacy_teardrops no)
	)
	(paper "A4")
	(title_block
		(title "pdpb — Lightning_PDPB_BRD.brd")
		(comment 1 "Lightning (Wiwynn / Facebook NVMe JBOF) / footprints 732-736 of 1140")
	)
	(layers
		(0 "F.Cu" signal "TOP")
		(4 "In1.Cu" signal "L2GND")
		(6 "In2.Cu" signal "L3")
		(8 "In3.Cu" signal "L4VCC")
		(10 "In4.Cu" signal "L5VCC")
		(12 "In5.Cu" signal "L6")
		(14 "In6.Cu" signal "L7GND")
		(2 "B.Cu" signal "BOTTOM")
		(9 "F.Adhes" user "F.Adhesive")
		(11 "B.Adhes" user "B.Adhesive")
		(13 "F.Paste" user "Package Geometry/Pastemask Top")
		(15 "B.Paste" user "Package Geometry/Pastemask Bottom")
		(5 "F.SilkS" user "Ref Des/Silkscreen Top")
		(7 "B.SilkS" user "Ref Des/Silkscreen Bottom")
		(1 "F.Mask" user "Board Geometry/Soldermask Top")
		(3 "B.Mask" user "Board Geometry/Soldermask Bottom")
		(17 "Dwgs.User" user "User.Drawings")
		(19 "Cmts.User" user "User.Comments")
		(21 "Eco1.User" user "User.Eco1")
		(23 "Eco2.User" user "User.Eco2")
		(25 "Edge.Cuts" user "Board Geometry/Outline")
		(27 "Margin" user)
		(31 "F.CrtYd" user "Package Geometry/Place Bound Top")
		(29 "B.CrtYd" user "Package Geometry/Place Bound Bottom")
		(35 "F.Fab" user "Ref Des/Assembly Top")
		(33 "B.Fab" user "Ref Des/Assembly Bottom")
	)
	(footprint ""
		(layer "F.Cu")
		(at 25.4 -236.982 180)
		(property "Reference" "PC1254"
			(at 0 0 180)
			(layer "F.SilkS")
			(hide yes)
			(effects
				(font
					(size 1.27 1.27)
				)
			)
		)
		(property "Value" "SCD1U25V3KX-GP"
			(at 0 -2.8194 180)
			(unlocked yes)
			(layer "F.Fab")
			(hide yes)
			(effects
				(font
					(size 1.016 1.016)
					(thickness 0.1524)
				)
			)
		)
		(property "Device Type" "C603H36"
			(at 0 -4.3434 180)
			(unlocked yes)
			(layer "F.Fab")
			(hide yes)
			(effects
				(font
					(size 1.016 1.016)
					(thickness 0.1524)
				)
			)
		)
		(duplicate_pad_numbers_are_jumpers no)
		(fp_line
			(start 0.508 0)
			(end -0.508 0)
			(stroke
				(width 0.2032)
				(type default)
			)
			(layer "F.SilkS")
		)
		(fp_rect
			(start -0.5842 1.3335)
			(end 0.5842 -1.3335)
			(stroke
				(width 0)
				(type default)
			)
			(fill no)
			(layer "F.CrtYd")
		)
		(fp_rect
			(start -0.5842 1.3335)
			(end 0.5842 -1.3335)
			(stroke
				(width 0)
				(type default)
			)
			(fill no)
			(layer "F.Fab")
		)
		(pad "1" smd custom
			(at 0 -0.762 180)
			(size 0.2159 0.2159)
			(layers "F.Cu" "F.Mask" "F.Paste")
			(net "P3V3")
			(options
				(clearance outline)
				(anchor circle)
			)
			(primitives
				(gr_poly
					(pts
						(arc
							(start -0.3302 -0.4318)
							(mid -0.402042 -0.402042)
							(end -0.4318 -0.3302)
						)
						(arc
							(start -0.4318 0.3302)
							(mid -0.402042 0.402042)
							(end -0.3302 0.4318)
						)
						(arc
							(start 0.3302 0.4318)
							(mid 0.402042 0.402042)
							(end 0.4318 0.3302)
						)
						(arc
							(start 0.4318 -0.3302)
							(mid 0.402042 -0.402042)
							(end 0.3302 -0.4318)
						)
					)
					(width 0)
					(fill yes)
				)
			)
		)
		(pad "2" smd custom
			(at 0 0.762 180)
			(size 0.2159 0.2159)
			(layers "F.Cu" "F.Mask" "F.Paste")
			(net "GND")
			(options
				(clearance outline)
				(anchor circle)
			)
			(primitives
				(gr_poly
					(pts
						(arc
							(start -0.3302 -0.4318)
							(mid -0.402042 -0.402042)
							(end -0.4318 -0.3302)
						)
						(arc
							(start -0.4318 0.3302)
							(mid -0.402042 0.402042)
							(end -0.3302 0.4318)
						)
						(arc
							(start 0.3302 0.4318)
							(mid 0.402042 0.402042)
							(end 0.4318 0.3302)
						)
						(arc
							(start 0.4318 -0.3302)
							(mid 0.402042 -0.402042)
							(end 0.3302 -0.4318)
						)
					)
					(width 0)
					(fill yes)
				)
			)
		)
	)
	(footprint ""
		(layer "F.Cu")
		(at 232.791 -436.626 90)
		(property "Reference" "PC1279"
			(at 0 0 90)
			(layer "F.SilkS")
			(hide yes)
			(effects
				(font
					(size 1.27 1.27)
				)
			)
		)
		(property "Value" "SC3300P50V2KX-1GP"
			(at 1.1811 -2.7051 90)
			(unlocked yes)
			(layer "F.Fab")
			(hide yes)
			(effects
				(font
					(size 1.016 1.016)
					(thickness 0.1524)
				)
			)
		)
		(property "Device Type" "C402H22"
			(at 1.1811 -4.2291 90)
			(unlocked yes)
			(layer "F.Fab")
			(hide yes)
			(effects
				(font
					(size 1.016 1.016)
					(thickness 0.1524)
				)
			)
		)
		(duplicate_pad_numbers_are_jumpers no)
		(fp_rect
			(start -0.4318 0.9525)
			(end 0.4318 -0.9525)
			(stroke
				(width 0)
				(type default)
			)
			(fill no)
			(layer "F.CrtYd")
		)
		(fp_rect
			(start -0.4318 0.9525)
			(end 0.4318 -0.9525)
			(stroke
				(width 0)
				(type default)
			)
			(fill no)
			(layer "F.Fab")
		)
		(pad "1" smd custom
			(at 0 -0.4445 90)
			(size 0.1524 0.1524)
			(layers "F.Cu" "F.Mask" "F.Paste")
			(net "P3V3_SS")
			(options
				(clearance outline)
				(anchor circle)
			)
			(primitives
				(gr_poly
					(pts
						(arc
							(start 0.3048 -0.2032)
							(mid 0.275042 -0.275042)
							(end 0.2032 -0.3048)
						)
						(arc
							(start -0.2032 -0.3048)
							(mid -0.275042 -0.275042)
							(end -0.3048 -0.2032)
						)
						(arc
							(start -0.3048 0.2032)
							(mid -0.275042 0.275042)
							(end -0.2032 0.3048)
						)
						(arc
							(start 0.2032 0.3048)
							(mid 0.275042 0.275042)
							(end 0.3048 0.2032)
						)
					)
					(width 0)
					(fill yes)
				)
			)
		)
		(pad "2" smd custom
			(at 0 0.4445 90)
			(size 0.1524 0.1524)
			(layers "F.Cu" "F.Mask" "F.Paste")
			(net "AGND_P3V3")
			(options
				(clearance outline)
				(anchor circle)
			)
			(primitives
				(gr_poly
					(pts
						(arc
							(start 0.3048 -0.2032)
							(mid 0.275042 -0.275042)
							(end 0.2032 -0.3048)
						)
						(arc
							(start -0.2032 -0.3048)
							(mid -0.275042 -0.275042)
							(end -0.3048 -0.2032)
						)
						(arc
							(start -0.3048 0.2032)
							(mid -0.275042 0.275042)
							(end -0.2032 0.3048)
						)
						(arc
							(start 0.2032 0.3048)
							(mid 0.275042 0.275042)
							(end 0.3048 0.2032)
						)
					)
					(width 0)
					(fill yes)
				)
			)
		)
	)
	(footprint ""
		(layer "F.Cu")
		(at 106.045 -434.848 180)
		(property "Reference" "C110"
			(at 0 0 180)
			(layer "F.SilkS")
			(hide yes)
			(effects
				(font
					(size 1.27 1.27)
				)
			)
		)
		(property "Value" "SC1KP50V2KX-1GP"
			(at 1.1811 -2.7051 180)
			(unlocked yes)
			(layer "F.Fab")
			(hide yes)
			(effects
				(font
					(size 1.016 1.016)
					(thickness 0.1524)
				)
			)
		)
		(property "Device Type" "C402H22"
			(at 1.1811 -4.2291 180)
			(unlocked yes)
			(layer "F.Fab")
			(hide yes)
			(effects
				(font
					(size 1.016 1.016)
					(thickness 0.1524)
				)
			)
		)
		(duplicate_pad_numbers_are_jumpers no)
		(fp_rect
			(start -0.4318 0.9525)
			(end 0.4318 -0.9525)
			(stroke
				(width 0)
				(type default)
			)
			(fill no)
			(layer "F.CrtYd")
		)
		(fp_rect
			(start -0.4318 0.9525)
			(end 0.4318 -0.9525)
			(stroke
				(width 0)
				(type default)
			)
			(fill no)
			(layer "F.Fab")
		)
		(pad "1" smd custom
			(at 0 -0.4445 180)
			(size 0.1524 0.1524)
			(layers "F.Cu" "F.Mask" "F.Paste")
			(net "SSD_PRSNT0")
			(options
				(clearance outline)
				(anchor circle)
			)
			(primitives
				(gr_poly
					(pts
						(arc
							(start 0.3048 -0.2032)
							(mid 0.275042 -0.275042)
							(end 0.2032 -0.3048)
						)
						(arc
							(start -0.2032 -0.3048)
							(mid -0.275042 -0.275042)
							(end -0.3048 -0.2032)
						)
						(arc
							(start -0.3048 0.2032)
							(mid -0.275042 0.275042)
							(end -0.2032 0.3048)
						)
						(arc
							(start 0.2032 0.3048)
							(mid 0.275042 0.275042)
							(end 0.3048 0.2032)
						)
					)
					(width 0)
					(fill yes)
				)
			)
		)
		(pad "2" smd custom
			(at 0 0.4445 180)
			(size 0.1524 0.1524)
			(layers "F.Cu" "F.Mask" "F.Paste")
			(net "GND")
			(options
				(clearance outline)
				(anchor circle)
			)
			(primitives
				(gr_poly
					(pts
						(arc
							(start 0.3048 -0.2032)
							(mid 0.275042 -0.275042)
							(end 0.2032 -0.3048)
						)
						(arc
							(start -0.2032 -0.3048)
							(mid -0.275042 -0.275042)
							(end -0.3048 -0.2032)
						)
						(arc
							(start -0.3048 0.2032)
							(mid -0.275042 0.275042)
							(end -0.2032 0.3048)
						)
						(arc
							(start 0.2032 0.3048)
							(mid 0.275042 0.275042)
							(end 0.3048 0.2032)
						)
					)
					(width 0)
					(fill yes)
				)
			)
		)
	)
	(footprint ""
		(layer "F.Cu")
		(at 52.2224 -244.088158 -90)
		(property "Reference" "R9830"
			(at 0 0 270)
			(layer "F.SilkS")
			(hide yes)
			(effects
				(font
					(size 1.27 1.27)
				)
			)
		)
		(property "Value" "0R2J-2-GP"
			(at 0.064008 -3.993896 270)
			(unlocked yes)
			(layer "F.Fab")
			(hide yes)
			(effects
				(font
					(size 1.016 1.016)
					(thickness 0.1524)
				)
			)
		)
		(property "Device Type" "R402H16"
			(at 0.064008 -5.517896 270)
			(unlocked yes)
			(layer "F.Fab")
			(hide yes)
			(effects
				(font
					(size 1.016 1.016)
					(thickness 0.1524)
				)
			)
		)
		(duplicate_pad_numbers_are_jumpers no)
		(fp_line
			(start -0.508 -0.9398)
			(end -0.508 0.9398)
			(stroke
				(width 0.1524)
				(type default)
			)
			(layer "F.SilkS")
		)
		(fp_line
			(start 0.508 -0.9398)
			(end -0.508 -0.9398)
			(stroke
				(width 0.1524)
				(type default)
			)
			(layer "F.SilkS")
		)
		(fp_rect
			(start -0.508 0.9398)
			(end 0.508 -0.9398)
			(stroke
				(width 0)
				(type default)
			)
			(fill no)
			(layer "F.CrtYd")
		)
		(fp_rect
			(start -0.508 0.9398)
			(end 0.508 -0.9398)
			(stroke
				(width 0)
				(type default)
			)
			(fill no)
			(layer "F.Fab")
		)
		(pad "1" smd custom
			(at 0 -0.4445 270)
			(size 0.1397 0.1397)
			(layers "F.Cu" "F.Mask" "F.Paste")
			(net "ATTN_LED_DR7_R")
			(options
				(clearance outline)
				(anchor circle)
			)
			(primitives
				(gr_poly
					(pts
						(arc
							(start -0.1778 -0.2794)
							(mid -0.249642 -0.249642)
							(end -0.2794 -0.1778)
						)
						(arc
							(start -0.2794 0.1778)
							(mid -0.249642 0.249642)
							(end -0.1778 0.2794)
						)
						(arc
							(start 0.1778 0.2794)
							(mid 0.249642 0.249642)
							(end 0.2794 0.1778)
						)
						(arc
							(start 0.2794 -0.1778)
							(mid 0.249642 -0.249642)
							(end 0.1778 -0.2794)
						)
					)
					(width 0)
					(fill yes)
				)
			)
		)
		(pad "2" smd custom
			(at 0 0.4445 270)
			(size 0.1397 0.1397)
			(layers "F.Cu" "F.Mask" "F.Paste")
			(net "ATTN_LED_DR7_N")
			(options
				(clearance outline)
				(anchor circle)
			)
			(primitives
				(gr_poly
					(pts
						(arc
							(start -0.1778 -0.2794)
							(mid -0.249642 -0.249642)
							(end -0.2794 -0.1778)
						)
						(arc
							(start -0.2794 0.1778)
							(mid -0.249642 0.249642)
							(end -0.1778 0.2794)
						)
						(arc
							(start 0.1778 0.2794)
							(mid 0.249642 0.249642)
							(end 0.2794 0.1778)
						)
						(arc
							(start 0.2794 -0.1778)
							(mid 0.249642 -0.249642)
							(end 0.1778 -0.2794)
						)
					)
					(width 0)
					(fill yes)
				)
			)
		)
	)
	(footprint ""
		(layer "F.Cu")
		(at 78.232 -154.178)
		(property "Reference" "SR977"
			(at 0 0 0)
			(layer "F.SilkS")
			(hide yes)
			(effects
				(font
					(size 1.27 1.27)
				)
			)
		)
		(property "Value" "2KR2F-3-GP"
			(at 0.064008 -3.993896 0)
			(unlocked yes)
			(layer "F.Fab")
			(hide yes)
			(effects
				(font
					(size 1.016 1.016)
					(thickness 0.1524)
				)
			)
		)
		(property "Device Type" "R402H16"
			(at 0.064008 -5.517896 0)
			(unlocked yes)
			(layer "F.Fab")
			(hide yes)
			(effects
				(font
					(size 1.016 1.016)
					(thickness 0.1524)
				)
			)
		)
		(duplicate_pad_numbers_are_jumpers no)
		(fp_line
			(start -0.508 -0.9398)
			(end -0.508 0.9398)
			(stroke
				(width 0.1524)
				(type default)
			)
			(layer "F.SilkS")
		)
		(fp_line
			(start 0.508 -0.9398)
			(end -0.508 -0.9398)
			(stroke
				(width 0.1524)
				(type default)
			)
			(layer "F.SilkS")
		)
		(fp_rect
			(start -0.508 0.9398)
			(end 0.508 -0.9398)
			(stroke
				(width 0)
				(type default)
			)
			(fill no)
			(layer "F.CrtYd")
		)
		(fp_rect
			(start -0.508 0.9398)
			(end 0.508 -0.9398)
			(stroke
				(width 0)
				(type default)
			)
			(fill no)
			(layer "F.Fab")
		)
		(pad "1" smd custom
			(at 0 -0.4445)
			(size 0.1397 0.1397)
			(layers "F.Cu" "F.Mask" "F.Paste")
			(net "P3V3")
			(options
				(clearance outline)
				(anchor circle)
			)
			(primitives
				(gr_poly
					(pts
						(arc
							(start -0.1778 -0.2794)
							(mid -0.249642 -0.249642)
							(end -0.2794 -0.1778)
						)
						(arc
							(start -0.2794 0.1778)
							(mid -0.249642 0.249642)
							(end -0.1778 0.2794)
						)
						(arc
							(start 0.1778 0.2794)
							(mid 0.249642 0.249642)
							(end 0.2794 0.1778)
						)
						(arc
							(start 0.2794 -0.1778)
							(mid 0.249642 -0.249642)
							(end 0.1778 -0.2794)
						)
					)
					(width 0)
					(fill yes)
				)
			)
		)
		(pad "2" smd custom
			(at 0 0.4445)
			(size 0.1397 0.1397)
			(layers "F.Cu" "F.Mask" "F.Paste")
			(net "SCL_DR3")
			(options
				(clearance outline)
				(anchor circle)
			)
			(primitives
				(gr_poly
					(pts
						(arc
							(start -0.1778 -0.2794)
							(mid -0.249642 -0.249642)
							(end -0.2794 -0.1778)
						)
						(arc
							(start -0.2794 0.1778)
							(mid -0.249642 0.249642)
							(end -0.1778 0.2794)
						)
						(arc
							(start 0.1778 0.2794)
							(mid 0.249642 0.249642)
							(end 0.2794 0.1778)
						)
						(arc
							(start 0.2794 -0.1778)
							(mid 0.249642 -0.249642)
							(end 0.1778 -0.2794)
						)
					)
					(width 0)
					(fill yes)
				)
			)
		)
	)
)
